(kicad_pcb
	(version 20260206)
	(generator "pcbnew")
	(generator_version "10.0")
	(general
		(thickness 1.6)
		(legacy_teardrops no)
	)
	(paper "A4")
	(title_block
		(title "03242023_DA0F0TMBIJ0_F0T_Motherboard_J_brd_V01_OCP.brd")
		(comment 1 "Grand Teton / footprints 5080-5086 of 6105")
	)
	(layers
		(0 "F.Cu" signal "TOP")
		(4 "In1.Cu" signal "GND")
		(6 "In2.Cu" signal "IN1")
		(8 "In3.Cu" signal "GND1")
		(10 "In4.Cu" signal "IN2")
		(12 "In5.Cu" signal "GND2")
		(14 "In6.Cu" signal "IN3")
		(16 "In7.Cu" signal "GND3")
		(18 "In8.Cu" signal "VCC")
		(20 "In9.Cu" signal "VCC1")
		(22 "In10.Cu" signal "GND4")
		(24 "In11.Cu" signal "IN4")
		(26 "In12.Cu" signal "GND5")
		(28 "In13.Cu" signal "IN5")
		(30 "In14.Cu" signal "GND6")
		(32 "In15.Cu" signal "IN6")
		(34 "In16.Cu" signal "GND7")
		(2 "B.Cu" signal "BOTTOM")
		(9 "F.Adhes" user "F.Adhesive")
		(11 "B.Adhes" user "B.Adhesive")
		(13 "F.Paste" user "Package Geometry/Pastemask Top")
		(15 "B.Paste" user "Package Geometry/Pastemask Bottom")
		(5 "F.SilkS" user "Ref Des/Silkscreen Top")
		(7 "B.SilkS" user "Ref Des/Silkscreen Bottom")
		(1 "F.Mask" user "Board Geometry/Soldermask Top")
		(3 "B.Mask" user "Board Geometry/Soldermask Bottom")
		(17 "Dwgs.User" user "User.Drawings")
		(19 "Cmts.User" user "User.Comments")
		(21 "Eco1.User" user "User.Eco1")
		(23 "Eco2.User" user "User.Eco2")
		(25 "Edge.Cuts" user "Board Geometry/Outline")
		(27 "Margin" user)
		(31 "F.CrtYd" user "Package Geometry/Place Bound Top")
		(29 "B.CrtYd" user "Package Geometry/Place Bound Bottom")
		(35 "F.Fab" user "Ref Des/Assembly Top")
		(33 "B.Fab" user "Ref Des/Assembly Bottom")
	)
	(footprint ""
		(layer "B.Cu")
		(at 118.370604 -296.05478)
		(property "Reference" "C352"
			(at 0 0 0)
			(layer "B.SilkS")
			(hide yes)
			(effects
				(font
					(size 1.27 1.27)
				)
				(justify mirror)
			)
		)
		(property "Value" ""
			(at 0 0 0)
			(layer "B.Fab")
			(effects
				(font
					(size 1.27 1.27)
				)
				(justify mirror)
			)
		)
		(duplicate_pad_numbers_are_jumpers no)
		(fp_line
			(start -1.524 -0.762)
			(end -1.524 0.762)
			(stroke
				(width 0.1524)
				(type default)
			)
			(layer "B.SilkS")
		)
		(fp_line
			(start -1.524 0.762)
			(end 1.524 0.762)
			(stroke
				(width 0.1524)
				(type default)
			)
			(layer "B.SilkS")
		)
		(fp_line
			(start 1.524 -0.762)
			(end -1.524 -0.762)
			(stroke
				(width 0.1524)
				(type default)
			)
			(layer "B.SilkS")
		)
		(fp_line
			(start 1.524 0.762)
			(end 1.524 -0.762)
			(stroke
				(width 0.1524)
				(type default)
			)
			(layer "B.SilkS")
		)
		(fp_line
			(start -1.1049 -0.724916)
			(end 1.1049 -0.724916)
			(stroke
				(width 0.1)
				(type default)
			)
			(layer "B.Fab")
		)
		(fp_line
			(start -1.1049 0.724916)
			(end -1.1049 -0.724916)
			(stroke
				(width 0.1)
				(type default)
			)
			(layer "B.Fab")
		)
		(fp_line
			(start 1.1049 -0.724916)
			(end 1.1049 0.724916)
			(stroke
				(width 0.1)
				(type default)
			)
			(layer "B.Fab")
		)
		(fp_line
			(start 1.1049 0.724916)
			(end -1.1049 0.724916)
			(stroke
				(width 0.1)
				(type default)
			)
			(layer "B.Fab")
		)
		(pad "1" smd rect
			(at 0.889 0)
			(size 1.016 1.27)
			(layers "B.Cu" "B.Mask" "B.Paste")
			(net "PVCCIN_CPU1")
		)
		(pad "2" smd rect
			(at -0.889 0)
			(size 1.016 1.27)
			(layers "B.Cu" "B.Mask" "B.Paste")
			(net "GND")
		)
	)
	(footprint ""
		(layer "B.Cu")
		(at 381.608584 -186.138058 90)
		(property "Reference" "R293"
			(at 0 0 90)
			(layer "B.SilkS")
			(hide yes)
			(effects
				(font
					(size 1.27 1.27)
				)
				(justify mirror)
			)
		)
		(property "Value" ""
			(at 0 0 90)
			(layer "B.Fab")
			(effects
				(font
					(size 1.27 1.27)
				)
				(justify mirror)
			)
		)
		(duplicate_pad_numbers_are_jumpers no)
		(fp_line
			(start 0.7874 -0.4064)
			(end -0.7874 -0.4064)
			(stroke
				(width 0.1524)
				(type default)
			)
			(layer "B.SilkS")
		)
		(fp_line
			(start -0.7874 -0.4064)
			(end -0.7874 0.4064)
			(stroke
				(width 0.1524)
				(type default)
			)
			(layer "B.SilkS")
		)
		(fp_line
			(start 0.7874 0.4064)
			(end 0.7874 -0.4064)
			(stroke
				(width 0.1524)
				(type default)
			)
			(layer "B.SilkS")
		)
		(fp_line
			(start -0.7874 0.4064)
			(end 0.7874 0.4064)
			(stroke
				(width 0.1524)
				(type default)
			)
			(layer "B.SilkS")
		)
		(fp_line
			(start 0.67945 -0.305054)
			(end 0.12065 -0.305054)
			(stroke
				(width 0.1)
				(type default)
			)
			(layer "B.Fab")
		)
		(fp_line
			(start 0.12065 -0.305054)
			(end 0.12065 -0.2794)
			(stroke
				(width 0.1)
				(type default)
			)
			(layer "B.Fab")
		)
		(fp_line
			(start -0.12065 -0.3048)
			(end -0.67945 -0.3048)
			(stroke
				(width 0.1)
				(type default)
			)
			(layer "B.Fab")
		)
		(fp_line
			(start -0.67945 -0.3048)
			(end -0.67945 0.3048)
			(stroke
				(width 0.1)
				(type default)
			)
			(layer "B.Fab")
		)
		(fp_line
			(start 0.12065 -0.2794)
			(end -0.12065 -0.2794)
			(stroke
				(width 0.1)
				(type default)
			)
			(layer "B.Fab")
		)
		(fp_line
			(start -0.12065 -0.2794)
			(end -0.12065 -0.3048)
			(stroke
				(width 0.1)
				(type default)
			)
			(layer "B.Fab")
		)
		(fp_line
			(start 0.12065 0.2794)
			(end 0.12065 0.3048)
			(stroke
				(width 0.1)
				(type default)
			)
			(layer "B.Fab")
		)
		(fp_line
			(start -0.120396 0.2794)
			(end 0.12065 0.2794)
			(stroke
				(width 0.1)
				(type default)
			)
			(layer "B.Fab")
		)
		(fp_line
			(start 0.67945 0.3048)
			(end 0.67945 -0.305054)
			(stroke
				(width 0.1)
				(type default)
			)
			(layer "B.Fab")
		)
		(fp_line
			(start 0.12065 0.3048)
			(end 0.67945 0.3048)
			(stroke
				(width 0.1)
				(type default)
			)
			(layer "B.Fab")
		)
		(fp_line
			(start -0.120396 0.3048)
			(end -0.120396 0.2794)
			(stroke
				(width 0.1)
				(type default)
			)
			(layer "B.Fab")
		)
		(fp_line
			(start -0.67945 0.3048)
			(end -0.120396 0.3048)
			(stroke
				(width 0.1)
				(type default)
			)
			(layer "B.Fab")
		)
		(pad "1" smd circle
			(at 0.40005 0 270)
			(size 0 0)
			(layers "B.Cu" "B.Mask" "B.Paste")
			(net "PD_CPU0_TXT_PLTEN")
		)
		(pad "2" smd circle
			(at -0.40005 0 270)
			(size 0 0)
			(layers "B.Cu" "B.Mask" "B.Paste")
			(net "GND")
		)
	)
	(footprint ""
		(layer "B.Cu")
		(at 82.180176 -346.808298 -90)
		(property "Reference" "PC490_P1_7"
			(at 0 0 90)
			(layer "B.SilkS")
			(hide yes)
			(effects
				(font
					(size 1.27 1.27)
				)
				(justify mirror)
			)
		)
		(property "Value" ""
			(at 0 0 90)
			(layer "B.Fab")
			(effects
				(font
					(size 1.27 1.27)
				)
				(justify mirror)
			)
		)
		(duplicate_pad_numbers_are_jumpers no)
		(fp_line
			(start -1.524 0.762)
			(end 1.524 0.762)
			(stroke
				(width 0.1524)
				(type default)
			)
			(layer "B.SilkS")
		)
		(fp_line
			(start 1.524 0.762)
			(end 1.524 -0.762)
			(stroke
				(width 0.1524)
				(type default)
			)
			(layer "B.SilkS")
		)
		(fp_line
			(start -1.524 -0.762)
			(end -1.524 0.762)
			(stroke
				(width 0.1524)
				(type default)
			)
			(layer "B.SilkS")
		)
		(fp_line
			(start 1.524 -0.762)
			(end -1.524 -0.762)
			(stroke
				(width 0.1524)
				(type default)
			)
			(layer "B.SilkS")
		)
		(fp_line
			(start -1.1049 0.724916)
			(end -1.1049 -0.724916)
			(stroke
				(width 0.1)
				(type default)
			)
			(layer "B.Fab")
		)
		(fp_line
			(start 1.1049 0.724916)
			(end -1.1049 0.724916)
			(stroke
				(width 0.1)
				(type default)
			)
			(layer "B.Fab")
		)
		(fp_line
			(start -1.1049 -0.724916)
			(end 1.1049 -0.724916)
			(stroke
				(width 0.1)
				(type default)
			)
			(layer "B.Fab")
		)
		(fp_line
			(start 1.1049 -0.724916)
			(end 1.1049 0.724916)
			(stroke
				(width 0.1)
				(type default)
			)
			(layer "B.Fab")
		)
		(pad "1" smd rect
			(at 0.889 0 270)
			(size 1.016 1.27)
			(layers "B.Cu" "B.Mask" "B.Paste")
			(net "SW_P12V_PVCCIN_CPU1_FLT")
		)
		(pad "2" smd rect
			(at -0.889 0 270)
			(size 1.016 1.27)
			(layers "B.Cu" "B.Mask" "B.Paste")
			(net "GND")
		)
	)
	(footprint ""
		(layer "B.Cu")
		(at 459.574646 -315.26099 -90)
		(property "Reference" "D45"
			(at 3.189732 1.218946 0)
			(unlocked yes)
			(layer "B.SilkS")
			(effects
				(font
					(size 0.7874 0.5842)
					(thickness 0.1524)
				)
				(justify left mirror)
			)
		)
		(property "Value" ""
			(at 0 0 90)
			(layer "B.Fab")
			(effects
				(font
					(size 1.27 1.27)
				)
				(justify mirror)
			)
		)
		(duplicate_pad_numbers_are_jumpers no)
		(fp_line
			(start -2.050796 0.700024)
			(end 2.050796 0.700024)
			(stroke
				(width 0.1524)
				(type default)
			)
			(layer "B.SilkS")
		)
		(fp_line
			(start 2.050796 0.700024)
			(end 2.050796 -0.700024)
			(stroke
				(width 0.1524)
				(type default)
			)
			(layer "B.SilkS")
		)
		(fp_line
			(start -2.343404 0.6985)
			(end -2.216404 0.6985)
			(stroke
				(width 0.1524)
				(type default)
			)
			(layer "B.SilkS")
		)
		(fp_line
			(start -2.229104 0.6985)
			(end -2.051304 0.6985)
			(stroke
				(width 0.1524)
				(type default)
			)
			(layer "B.SilkS")
		)
		(fp_line
			(start -2.051304 0.6985)
			(end -2.051304 0.635)
			(stroke
				(width 0.1524)
				(type default)
			)
			(layer "B.SilkS")
		)
		(fp_line
			(start -2.152904 0.635)
			(end -2.152904 -0.6985)
			(stroke
				(width 0.1524)
				(type default)
			)
			(layer "B.SilkS")
		)
		(fp_line
			(start -2.051304 0.635)
			(end -2.152904 0.635)
			(stroke
				(width 0.1524)
				(type default)
			)
			(layer "B.SilkS")
		)
		(fp_line
			(start 0.30607 0.500126)
			(end -0.193802 0)
			(stroke
				(width 0.1524)
				(type default)
			)
			(layer "B.SilkS")
		)
		(fp_line
			(start -0.193802 0)
			(end 0.30607 -0.500126)
			(stroke
				(width 0.1524)
				(type default)
			)
			(layer "B.SilkS")
		)
		(fp_line
			(start -0.293878 -0.500126)
			(end -0.293878 0.500126)
			(stroke
				(width 0.1524)
				(type default)
			)
			(layer "B.SilkS")
		)
		(fp_line
			(start 0.30607 -0.500126)
			(end 0.30607 0.500126)
			(stroke
				(width 0.1524)
				(type default)
			)
			(layer "B.SilkS")
		)
		(fp_line
			(start -2.064004 -0.6731)
			(end -2.064004 -0.6985)
			(stroke
				(width 0.1524)
				(type default)
			)
			(layer "B.SilkS")
		)
		(fp_line
			(start -2.343404 -0.6985)
			(end -2.343404 0.6985)
			(stroke
				(width 0.1524)
				(type default)
			)
			(layer "B.SilkS")
		)
		(fp_line
			(start -2.229104 -0.6985)
			(end -2.229104 0.6985)
			(stroke
				(width 0.1524)
				(type default)
			)
			(layer "B.SilkS")
		)
		(fp_line
			(start -2.152904 -0.6985)
			(end -2.343404 -0.6985)
			(stroke
				(width 0.1524)
				(type default)
			)
			(layer "B.SilkS")
		)
		(fp_line
			(start -2.064004 -0.6985)
			(end -2.229104 -0.6985)
			(stroke
				(width 0.1524)
				(type default)
			)
			(layer "B.SilkS")
		)
		(fp_line
			(start -2.050796 -0.700024)
			(end -2.050796 0.700024)
			(stroke
				(width 0.1524)
				(type default)
			)
			(layer "B.SilkS")
		)
		(fp_line
			(start 2.050796 -0.700024)
			(end -2.050796 -0.700024)
			(stroke
				(width 0.1524)
				(type default)
			)
			(layer "B.SilkS")
		)
		(fp_line
			(start -0.899922 0.700024)
			(end 0.899922 0.700024)
			(stroke
				(width 0.1)
				(type default)
			)
			(layer "B.Fab")
		)
		(fp_line
			(start 0.899922 0.700024)
			(end 0.899922 -0.700024)
			(stroke
				(width 0.1)
				(type default)
			)
			(layer "B.Fab")
		)
		(fp_line
			(start -0.899922 -0.700024)
			(end -0.899922 0.700024)
			(stroke
				(width 0.1)
				(type default)
			)
			(layer "B.Fab")
		)
		(fp_line
			(start 0.899922 -0.700024)
			(end -0.899922 -0.700024)
			(stroke
				(width 0.1)
				(type default)
			)
			(layer "B.Fab")
		)
		(fp_text user "+"
			(at 3.123946 0.762 180)
			(unlocked yes)
			(layer "B.SilkS")
			(effects
				(font
					(size 1.905 1.4224)
					(thickness 0.1524)
				)
				(justify left mirror)
			)
		)
		(fp_text user "-"
			(at -2.003298 -3.303524 90)
			(unlocked yes)
			(layer "B.SilkS")
			(effects
				(font
					(size 1.905 1.4224)
					(thickness 0.1524)
				)
				(justify left mirror)
			)
		)
		(fp_text user "+"
			(at 3.123946 0.762 180)
			(unlocked yes)
			(layer "B.Fab")
			(effects
				(font
					(size 1.905 1.4224)
					(thickness 0.1524)
				)
				(justify left mirror)
			)
		)
		(fp_text user "-"
			(at -3.880104 0.23495 90)
			(unlocked yes)
			(layer "B.Fab")
			(effects
				(font
					(size 1.905 1.4224)
					(thickness 0.1524)
				)
				(justify left mirror)
			)
		)
		(pad "1" smd rect
			(at 1.199896 0 180)
			(size 0.6604 1.3716)
			(layers "B.Cu" "B.Mask" "B.Paste")
			(net "PWRGD_FAIL_CPU0_GH_R1")
		)
		(pad "2" smd rect
			(at -1.199896 0)
			(size 0.6604 1.3716)
			(layers "B.Cu" "B.Mask" "B.Paste")
			(net "P3V3_AUX")
		)
	)
	(footprint ""
		(layer "B.Cu")
		(at 372.41988 -36.921948 180)
		(property "Reference" "R2511"
			(at 0 0 0)
			(layer "B.SilkS")
			(hide yes)
			(effects
				(font
					(size 1.27 1.27)
				)
				(justify mirror)
			)
		)
		(property "Value" ""
			(at 0 0 0)
			(layer "B.Fab")
			(effects
				(font
					(size 1.27 1.27)
				)
				(justify mirror)
			)
		)
		(duplicate_pad_numbers_are_jumpers no)
		(fp_line
			(start 0.7874 0.4064)
			(end 0.7874 -0.4064)
			(stroke
				(width 0.1524)
				(type default)
			)
			(layer "B.SilkS")
		)
		(fp_line
			(start 0.7874 -0.4064)
			(end -0.7874 -0.4064)
			(stroke
				(width 0.1524)
				(type default)
			)
			(layer "B.SilkS")
		)
		(fp_line
			(start -0.7874 0.4064)
			(end 0.7874 0.4064)
			(stroke
				(width 0.1524)
				(type default)
			)
			(layer "B.SilkS")
		)
		(fp_line
			(start -0.7874 -0.4064)
			(end -0.7874 0.4064)
			(stroke
				(width 0.1524)
				(type default)
			)
			(layer "B.SilkS")
		)
		(fp_line
			(start 0.67945 0.3048)
			(end 0.67945 -0.305054)
			(stroke
				(width 0.1)
				(type default)
			)
			(layer "B.Fab")
		)
		(fp_line
			(start 0.67945 -0.305054)
			(end 0.12065 -0.305054)
			(stroke
				(width 0.1)
				(type default)
			)
			(layer "B.Fab")
		)
		(fp_line
			(start 0.12065 0.3048)
			(end 0.67945 0.3048)
			(stroke
				(width 0.1)
				(type default)
			)
			(layer "B.Fab")
		)
		(fp_line
			(start 0.12065 0.2794)
			(end 0.12065 0.3048)
			(stroke
				(width 0.1)
				(type default)
			)
			(layer "B.Fab")
		)
		(fp_line
			(start 0.12065 -0.2794)
			(end -0.12065 -0.2794)
			(stroke
				(width 0.1)
				(type default)
			)
			(layer "B.Fab")
		)
		(fp_line
			(start 0.12065 -0.305054)
			(end 0.12065 -0.2794)
			(stroke
				(width 0.1)
				(type default)
			)
			(layer "B.Fab")
		)
		(fp_line
			(start -0.120396 0.3048)
			(end -0.120396 0.2794)
			(stroke
				(width 0.1)
				(type default)
			)
			(layer "B.Fab")
		)
		(fp_line
			(start -0.120396 0.2794)
			(end 0.12065 0.2794)
			(stroke
				(width 0.1)
				(type default)
			)
			(layer "B.Fab")
		)
		(fp_line
			(start -0.12065 -0.2794)
			(end -0.12065 -0.3048)
			(stroke
				(width 0.1)
				(type default)
			)
			(layer "B.Fab")
		)
		(fp_line
			(start -0.12065 -0.3048)
			(end -0.67945 -0.3048)
			(stroke
				(width 0.1)
				(type default)
			)
			(layer "B.Fab")
		)
		(fp_line
			(start -0.67945 0.3048)
			(end -0.120396 0.3048)
			(stroke
				(width 0.1)
				(type default)
			)
			(layer "B.Fab")
		)
		(fp_line
			(start -0.67945 -0.3048)
			(end -0.67945 0.3048)
			(stroke
				(width 0.1)
				(type default)
			)
			(layer "B.Fab")
		)
		(pad "1" smd circle
			(at 0.40005 0)
			(size 0 0)
			(layers "B.Cu" "B.Mask" "B.Paste")
			(net "FM_M2_E1S_E6_PEDET")
		)
		(pad "2" smd circle
			(at -0.40005 0)
			(size 0 0)
			(layers "B.Cu" "B.Mask" "B.Paste")
			(net "GND")
		)
	)
	(footprint ""
		(layer "B.Cu")
		(at 287.899094 -317.876682 180)
		(property "Reference" "R3877"
			(at 0 0 0)
			(layer "B.SilkS")
			(hide yes)
			(effects
				(font
					(size 1.27 1.27)
				)
				(justify mirror)
			)
		)
		(property "Value" ""
			(at 0 0 0)
			(layer "B.Fab")
			(effects
				(font
					(size 1.27 1.27)
				)
				(justify mirror)
			)
		)
		(duplicate_pad_numbers_are_jumpers no)
		(fp_line
			(start 0.7874 0.4064)
			(end 0.7874 -0.4064)
			(stroke
				(width 0.1524)
				(type default)
			)
			(layer "B.SilkS")
		)
		(fp_line
			(start 0.7874 -0.4064)
			(end -0.7874 -0.4064)
			(stroke
				(width 0.1524)
				(type default)
			)
			(layer "B.SilkS")
		)
		(fp_line
			(start -0.7874 0.4064)
			(end 0.7874 0.4064)
			(stroke
				(width 0.1524)
				(type default)
			)
			(layer "B.SilkS")
		)
		(fp_line
			(start -0.7874 -0.4064)
			(end -0.7874 0.4064)
			(stroke
				(width 0.1524)
				(type default)
			)
			(layer "B.SilkS")
		)
		(fp_line
			(start 0.67945 0.3048)
			(end 0.67945 -0.305054)
			(stroke
				(width 0.1)
				(type default)
			)
			(layer "B.Fab")
		)
		(fp_line
			(start 0.67945 -0.305054)
			(end 0.12065 -0.305054)
			(stroke
				(width 0.1)
				(type default)
			)
			(layer "B.Fab")
		)
		(fp_line
			(start 0.12065 0.3048)
			(end 0.67945 0.3048)
			(stroke
				(width 0.1)
				(type default)
			)
			(layer "B.Fab")
		)
		(fp_line
			(start 0.12065 0.2794)
			(end 0.12065 0.3048)
			(stroke
				(width 0.1)
				(type default)
			)
			(layer "B.Fab")
		)
		(fp_line
			(start 0.12065 -0.2794)
			(end -0.12065 -0.2794)
			(stroke
				(width 0.1)
				(type default)
			)
			(layer "B.Fab")
		)
		(fp_line
			(start 0.12065 -0.305054)
			(end 0.12065 -0.2794)
			(stroke
				(width 0.1)
				(type default)
			)
			(layer "B.Fab")
		)
		(fp_line
			(start -0.120396 0.3048)
			(end -0.120396 0.2794)
			(stroke
				(width 0.1)
				(type default)
			)
			(layer "B.Fab")
		)
		(fp_line
			(start -0.120396 0.2794)
			(end 0.12065 0.2794)
			(stroke
				(width 0.1)
				(type default)
			)
			(layer "B.Fab")
		)
		(fp_line
			(start -0.12065 -0.2794)
			(end -0.12065 -0.3048)
			(stroke
				(width 0.1)
				(type default)
			)
			(layer "B.Fab")
		)
		(fp_line
			(start -0.12065 -0.3048)
			(end -0.67945 -0.3048)
			(stroke
				(width 0.1)
				(type default)
			)
			(layer "B.Fab")
		)
		(fp_line
			(start -0.67945 0.3048)
			(end -0.120396 0.3048)
			(stroke
				(width 0.1)
				(type default)
			)
			(layer "B.Fab")
		)
		(fp_line
			(start -0.67945 -0.3048)
			(end -0.67945 0.3048)
			(stroke
				(width 0.1)
				(type default)
			)
			(layer "B.Fab")
		)
		(pad "1" smd circle
			(at 0.40005 0)
			(size 0 0)
			(layers "B.Cu" "B.Mask" "B.Paste")
			(net "I3C_SPD_DDRABCD_CPU0_LVC1_SCL_2")
		)
		(pad "2" smd circle
			(at -0.40005 0)
			(size 0 0)
			(layers "B.Cu" "B.Mask" "B.Paste")
			(net "I3C_SPD_DDRABCD_CPU0_LVC1_SCL")
		)
	)
	(footprint ""
		(layer "B.Cu")
		(at 166.369746 -321.554856 -90)
		(property "Reference" "C94"
			(at 0 0 90)
			(layer "B.SilkS")
			(hide yes)
			(effects
				(font
					(size 1.27 1.27)
				)
				(justify mirror)
			)
		)
		(property "Value" ""
			(at 0 0 90)
			(layer "B.Fab")
			(effects
				(font
					(size 1.27 1.27)
				)
				(justify mirror)
			)
		)
		(duplicate_pad_numbers_are_jumpers no)
		(fp_line
			(start -1.524 0.762)
			(end 1.524 0.762)
			(stroke
				(width 0.1524)
				(type default)
			)
			(layer "B.SilkS")
		)
		(fp_line
			(start 1.524 0.762)
			(end 1.524 -0.762)
			(stroke
				(width 0.1524)
				(type default)
			)
			(layer "B.SilkS")
		)
		(fp_line
			(start -1.524 -0.762)
			(end -1.524 0.762)
			(stroke
				(width 0.1524)
				(type default)
			)
			(layer "B.SilkS")
		)
		(fp_line
			(start 1.524 -0.762)
			(end -1.524 -0.762)
			(stroke
				(width 0.1524)
				(type default)
			)
			(layer "B.SilkS")
		)
		(fp_line
			(start -1.1049 0.724916)
			(end -1.1049 -0.724916)
			(stroke
				(width 0.1)
				(type default)
			)
			(layer "B.Fab")
		)
		(fp_line
			(start 1.1049 0.724916)
			(end -1.1049 0.724916)
			(stroke
				(width 0.1)
				(type default)
			)
			(layer "B.Fab")
		)
		(fp_line
			(start -1.1049 -0.724916)
			(end 1.1049 -0.724916)
			(stroke
				(width 0.1)
				(type default)
			)
			(layer "B.Fab")
		)
		(fp_line
			(start 1.1049 -0.724916)
			(end 1.1049 0.724916)
			(stroke
				(width 0.1)
				(type default)
			)
			(layer "B.Fab")
		)
		(pad "1" smd rect
			(at 0.889 0 270)
			(size 1.016 1.27)
			(layers "B.Cu" "B.Mask" "B.Paste")
			(net "P12V_S3_AUX_CPU1_NVDIMM")
		)
		(pad "2" smd rect
			(at -0.889 0 270)
			(size 1.016 1.27)
			(layers "B.Cu" "B.Mask" "B.Paste")
			(net "GND")
		)
	)
)
